FILE_TYPE = MACRO_DRAWING;
SET COLOR_WIRE YELLOW;
SET COLOR_PROP ORANGE;
SET COLOR_DOT WHITE;
SET COLOR_ARC YELLOW;
SET COLOR_BODY GREEN;
SET COLOR_NOTE PURPLE;
SET PROP_DISPLAY VALUE;
SET PAGE_NUMBER P20;
FORCEADD TABLE_COVER..1
(2100 1650);
FORCEPROP 2 LAST CUSTOM_TXT_CDS <XR_PAGE_TITLE>
J 0
(-5270 7350);
DISPLAY 0.638298 (-5270 7350);
PAINT PINK (-5270 7350);
FORCEPROP 1 LAST CUSTOM_TXT_CDS <TITLE>
J 1
(190 2255);
DISPLAY 0.978723 (190 2255);
FORCEPROP 1 LAST CUSTOM_TXT_CDS <CON_TOTAL_PAGES>
J 0
(225 1700);
DISPLAY 0.978723 (225 1700);
FORCEPROP 1 LAST CUSTOM_TXT_CDS <CON_PAGE_NUM>
J 0
(-105 1700);
DISPLAY 0.978723 (-105 1700);
FORCEPROP 1 LAST CUSTOM_TXT_CDS <DATE>
J 0
(1375 1850);
DISPLAY 0.978723 (1375 1850);
FORCEPROP 1 LAST CUSTOM_TXT_CDS <DESIGNER>
J 0
(1375 2225);
DISPLAY 0.978723 (1375 2225);
FORCEPROP 1 LAST CUSTOM_TXT_CDS <ASSY_PN>
J 0
(125 1825);
DISPLAY 0.978723 (125 1825);
FORCEPROP 1 LAST CUSTOM_TXT_CDS <DOCNO>
J 0
(125 2035);
DISPLAY 0.978723 (125 2035);
FORCEPROP 1 LAST CUSTOM_TXT_CDS <DOCREV>
J 0
(1375 2025);
DISPLAY 0.978723 (1375 2025);
FORCEPROP 1 LAST DESCRIPTION X4 PCIE TIME CARD
J 0
(-2100 5100);
DISPLAY 2.361702 (-2100 5100);
FORCEPROP 1 LAST PROJECT TIME CARD
J 0
(-2100 5825);
DISPLAY 2.957447 (-2100 5825);
FORCEPROP 1 LAST APPROVER <name>
J 0
(-2075 3200);
DISPLAY 1.893617 (-2075 3200);
FORCEPROP 1 LAST VIEWER <name>
J 0
(-2075 3625);
DISPLAY 1.893617 (-2075 3625);
FORCEPROP 1 LAST DESIGNER <name>
J 0
(-2075 4075);
DISPLAY 1.893617 (-2075 4075);
FORCEPROP 1 LAST TITLE COVER
J 0
(-400 2450);
DISPLAY 1.212766 (-400 2450);
PAINT GREEN (-400 2450);
DISPLAY INVISIBLE (-400 2450);
FORCEPROP 2 LAST PAGE_BORDER TRUE
J 0
(-5270 7350);
DISPLAY 0.638298 (-5270 7350);
PAINT PINK (-5270 7350);
DISPLAY INVISIBLE (-5270 7350);
FORCEPROP 1 LAST CDS_LMAN_SYM_OUTLINE -7700,5800,200,-200
J 0
(2100 1650);
DISPLAY 0.468085 (2100 1650);
PAINT GREEN (2100 1650);
DISPLAY INVISIBLE (2100 1650);
FORCEPROP 2 LAST CDS_LIB cls
J 0
(2100 1650);
DISPLAY INVISIBLE (2100 1650);
FORCEPROP 1 LAST COMMENT_BODY TRUE
J 0
(2110 1705);
DISPLAY 0.808511 (2110 1705);
DISPLAY INVISIBLE (2110 1705);
FORCEPROP 2 LAST CDS_XR_PAGE_TITLE CR-1 : @TIMECARD_LIB.TIMECARD(SCH_1):PAGE1
J 0
(-5270 7350);
DISPLAY 0.638298 (-5270 7350);
PAINT PINK (-5270 7350);
DISPLAY INVISIBLE (-5270 7350);
FORCENOTE
R4006-G0001-03-SC REV2.0
(-3750 2850) 0;
DISPLAY LEFT (-3750 2850);
DISPLAY 1.021277 (-3750 2850);
FORCENOTE
- SCHEMATIC RELEASE FOR PCBA CPN:R4006-G0001-03 REV03.
(-3600 2650) 0;
DISPLAY LEFT (-3600 2650);
DISPLAY 0.808511 (-3600 2650);
FORCENOTE
- MANUALLY CHANGE U34 FROM G222-00082-01 TO G229-10017-01 FOR THE BOM FILE.
(-3400 2300) 0;
DISPLAY LEFT (-3400 2300);
DISPLAY 0.808511 (-3400 2300);
FORCENOTE
- SCHEMATIC RELEASE DATE: SEP 02, 2022.
(-3600 2750) 0;
DISPLAY LEFT (-3600 2750);
DISPLAY 0.808511 (-3600 2750);
FORCENOTE
MP:
(-3750 2750) 0;
DISPLAY LEFT (-3750 2750);
DISPLAY 0.808511 (-3750 2750);
FORCENOTE
BOM NOTE:
(-3750 2300) 0;
DISPLAY LEFT (-3750 2300);
DISPLAY 0.808511 (-3750 2300);
FORCENOTE
- MANUALLY CHANGE U23 FROM G221-10224-01 TO G221-10359-01 FOR THE BOM FILE.
(-3400 2200) 0;
DISPLAY LEFT (-3400 2200);
DISPLAY 0.808511 (-3400 2200);
FORCENOTE
PCB CPN: R4006-B0001-02_R01.
(-400 2500) 0;
DISPLAY LEFT (-400 2500);
DISPLAY 1.276596 (-400 2500);
QUIT
